(kicad_pcb
	(version 20260206)
	(generator "pcbnew")
	(generator_version "10.0")
	(general
		(thickness 1.6)
		(legacy_teardrops no)
	)
	(paper "A4")
	(title_block
		(title "dpb — 14545-sa.0730WZS0815.brd")
		(comment 1 "Honey Badger (Wiwynn) / footprints 701-707 of 1066")
	)
	(layers
		(0 "F.Cu" signal "TOP")
		(4 "In1.Cu" signal "L2GND")
		(6 "In2.Cu" signal "L3")
		(8 "In3.Cu" signal "L4VCC")
		(10 "In4.Cu" signal "L5VCC")
		(12 "In5.Cu" signal "L6")
		(14 "In6.Cu" signal "L7GND")
		(2 "B.Cu" signal "BOTTOM")
		(9 "F.Adhes" user "F.Adhesive")
		(11 "B.Adhes" user "B.Adhesive")
		(13 "F.Paste" user "Package Geometry/Pastemask Top")
		(15 "B.Paste" user "Package Geometry/Pastemask Bottom")
		(5 "F.SilkS" user "Ref Des/Silkscreen Top")
		(7 "B.SilkS" user "Ref Des/Silkscreen Bottom")
		(1 "F.Mask" user "Board Geometry/Soldermask Top")
		(3 "B.Mask" user "Board Geometry/Soldermask Bottom")
		(17 "Dwgs.User" user "User.Drawings")
		(19 "Cmts.User" user "User.Comments")
		(21 "Eco1.User" user "User.Eco1")
		(23 "Eco2.User" user "User.Eco2")
		(25 "Edge.Cuts" user "Board Geometry/Outline")
		(27 "Margin" user)
		(31 "F.CrtYd" user "Package Geometry/Place Bound Top")
		(29 "B.CrtYd" user "Package Geometry/Place Bound Bottom")
		(35 "F.Fab" user "Ref Des/Assembly Top")
		(33 "B.Fab" user "Ref Des/Assembly Bottom")
	)
	(footprint ""
		(layer "F.Cu")
		(at 27.228546 -245.8339 -90)
		(property "Reference" "R368"
			(at 0 0 270)
			(layer "F.SilkS")
			(hide yes)
			(effects
				(font
					(size 1.27 1.27)
				)
			)
		)
		(property "Value" "4K7R2J-2-GP"
			(at 0.064008 -3.993896 270)
			(unlocked yes)
			(layer "F.Fab")
			(hide yes)
			(effects
				(font
					(size 1.016 1.016)
					(thickness 0.1524)
				)
			)
		)
		(property "Device Type" "R402H16"
			(at 0.064008 -5.517896 270)
			(unlocked yes)
			(layer "F.Fab")
			(hide yes)
			(effects
				(font
					(size 1.016 1.016)
					(thickness 0.1524)
				)
			)
		)
		(duplicate_pad_numbers_are_jumpers no)
		(fp_line
			(start -0.508 -0.9398)
			(end -0.508 0.9398)
			(stroke
				(width 0.1524)
				(type default)
			)
			(layer "F.SilkS")
		)
		(fp_line
			(start 0.508 -0.9398)
			(end -0.508 -0.9398)
			(stroke
				(width 0.1524)
				(type default)
			)
			(layer "F.SilkS")
		)
		(fp_rect
			(start -0.508 0.9398)
			(end 0.508 -0.9398)
			(stroke
				(width 0)
				(type default)
			)
			(fill no)
			(layer "F.CrtYd")
		)
		(fp_rect
			(start -0.508 0.9398)
			(end 0.508 -0.9398)
			(stroke
				(width 0)
				(type default)
			)
			(fill no)
			(layer "F.Fab")
		)
		(pad "1" smd custom
			(at 0 -0.4445 270)
			(size 0.1397 0.1397)
			(layers "F.Cu" "F.Mask" "F.Paste")
			(net "P3V3")
			(options
				(clearance outline)
				(anchor circle)
			)
			(primitives
				(gr_poly
					(pts
						(arc
							(start -0.1778 -0.2794)
							(mid -0.249642 -0.249642)
							(end -0.2794 -0.1778)
						)
						(arc
							(start -0.2794 0.1778)
							(mid -0.249642 0.249642)
							(end -0.1778 0.2794)
						)
						(arc
							(start 0.1778 0.2794)
							(mid 0.249642 0.249642)
							(end 0.2794 0.1778)
						)
						(arc
							(start 0.2794 -0.1778)
							(mid 0.249642 -0.249642)
							(end 0.1778 -0.2794)
						)
					)
					(width 0)
					(fill yes)
				)
			)
		)
		(pad "2" smd custom
			(at 0 0.4445 270)
			(size 0.1397 0.1397)
			(layers "F.Cu" "F.Mask" "F.Paste")
			(net "I2C_B_SDA")
			(options
				(clearance outline)
				(anchor circle)
			)
			(primitives
				(gr_poly
					(pts
						(arc
							(start -0.1778 -0.2794)
							(mid -0.249642 -0.249642)
							(end -0.2794 -0.1778)
						)
						(arc
							(start -0.2794 0.1778)
							(mid -0.249642 0.249642)
							(end -0.1778 0.2794)
						)
						(arc
							(start 0.1778 0.2794)
							(mid 0.249642 0.249642)
							(end 0.2794 0.1778)
						)
						(arc
							(start 0.2794 -0.1778)
							(mid 0.249642 -0.249642)
							(end 0.1778 -0.2794)
						)
					)
					(width 0)
					(fill yes)
				)
			)
		)
	)
	(footprint ""
		(layer "F.Cu")
		(at 77.851 -402.463 180)
		(property "Reference" "C385"
			(at 0 0 180)
			(layer "F.SilkS")
			(hide yes)
			(effects
				(font
					(size 1.27 1.27)
				)
			)
		)
		(property "Value" "SCD033U25V2KX-GP"
			(at 1.1811 -2.7051 180)
			(unlocked yes)
			(layer "F.Fab")
			(hide yes)
			(effects
				(font
					(size 1.016 1.016)
					(thickness 0.1524)
				)
			)
		)
		(property "Device Type" "C402H22"
			(at 1.1811 -4.2291 180)
			(unlocked yes)
			(layer "F.Fab")
			(hide yes)
			(effects
				(font
					(size 1.016 1.016)
					(thickness 0.1524)
				)
			)
		)
		(duplicate_pad_numbers_are_jumpers no)
		(fp_rect
			(start -0.4318 0.9525)
			(end 0.4318 -0.9525)
			(stroke
				(width 0)
				(type default)
			)
			(fill no)
			(layer "F.CrtYd")
		)
		(fp_rect
			(start -0.4318 0.9525)
			(end 0.4318 -0.9525)
			(stroke
				(width 0)
				(type default)
			)
			(fill no)
			(layer "F.Fab")
		)
		(pad "1" smd custom
			(at 0 -0.4445 180)
			(size 0.1524 0.1524)
			(layers "F.Cu" "F.Mask" "F.Paste")
			(net "P12V")
			(options
				(clearance outline)
				(anchor circle)
			)
			(primitives
				(gr_poly
					(pts
						(arc
							(start 0.3048 -0.2032)
							(mid 0.275042 -0.275042)
							(end 0.2032 -0.3048)
						)
						(arc
							(start -0.2032 -0.3048)
							(mid -0.275042 -0.275042)
							(end -0.3048 -0.2032)
						)
						(arc
							(start -0.3048 0.2032)
							(mid -0.275042 0.275042)
							(end -0.2032 0.3048)
						)
						(arc
							(start 0.2032 0.3048)
							(mid 0.275042 0.275042)
							(end 0.3048 0.2032)
						)
					)
					(width 0)
					(fill yes)
				)
			)
		)
		(pad "2" smd custom
			(at 0 0.4445 180)
			(size 0.1524 0.1524)
			(layers "F.Cu" "F.Mask" "F.Paste")
			(net "SW_HDD6_N")
			(options
				(clearance outline)
				(anchor circle)
			)
			(primitives
				(gr_poly
					(pts
						(arc
							(start 0.3048 -0.2032)
							(mid 0.275042 -0.275042)
							(end 0.2032 -0.3048)
						)
						(arc
							(start -0.2032 -0.3048)
							(mid -0.275042 -0.275042)
							(end -0.3048 -0.2032)
						)
						(arc
							(start -0.3048 0.2032)
							(mid -0.275042 0.275042)
							(end -0.2032 0.3048)
						)
						(arc
							(start 0.2032 0.3048)
							(mid 0.275042 0.275042)
							(end 0.3048 0.2032)
						)
					)
					(width 0)
					(fill yes)
				)
			)
		)
	)
	(footprint ""
		(layer "F.Cu")
		(at 224.6884 -453.7202 90)
		(property "Reference" "R102"
			(at 0 0 90)
			(layer "F.SilkS")
			(hide yes)
			(effects
				(font
					(size 1.27 1.27)
				)
			)
		)
		(property "Value" "402R2F-GP"
			(at 0.064008 -3.993896 90)
			(unlocked yes)
			(layer "F.Fab")
			(hide yes)
			(effects
				(font
					(size 1.016 1.016)
					(thickness 0.1524)
				)
			)
		)
		(property "Device Type" "R402H16"
			(at 0.064008 -5.517896 90)
			(unlocked yes)
			(layer "F.Fab")
			(hide yes)
			(effects
				(font
					(size 1.016 1.016)
					(thickness 0.1524)
				)
			)
		)
		(duplicate_pad_numbers_are_jumpers no)
		(fp_line
			(start 0.508 -0.9398)
			(end -0.508 -0.9398)
			(stroke
				(width 0.1524)
				(type default)
			)
			(layer "F.SilkS")
		)
		(fp_line
			(start -0.508 -0.9398)
			(end -0.508 0.9398)
			(stroke
				(width 0.1524)
				(type default)
			)
			(layer "F.SilkS")
		)
		(fp_rect
			(start -0.508 0.9398)
			(end 0.508 -0.9398)
			(stroke
				(width 0)
				(type default)
			)
			(fill no)
			(layer "F.CrtYd")
		)
		(fp_rect
			(start -0.508 0.9398)
			(end 0.508 -0.9398)
			(stroke
				(width 0)
				(type default)
			)
			(fill no)
			(layer "F.Fab")
		)
		(pad "1" smd custom
			(at 0 -0.4445 90)
			(size 0.1397 0.1397)
			(layers "F.Cu" "F.Mask" "F.Paste")
			(net "P5VA_HDD0_LED")
			(options
				(clearance outline)
				(anchor circle)
			)
			(primitives
				(gr_poly
					(pts
						(arc
							(start -0.1778 -0.2794)
							(mid -0.249642 -0.249642)
							(end -0.2794 -0.1778)
						)
						(arc
							(start -0.2794 0.1778)
							(mid -0.249642 0.249642)
							(end -0.1778 0.2794)
						)
						(arc
							(start 0.1778 0.2794)
							(mid 0.249642 0.249642)
							(end 0.2794 0.1778)
						)
						(arc
							(start 0.2794 -0.1778)
							(mid 0.249642 -0.249642)
							(end 0.1778 -0.2794)
						)
					)
					(width 0)
					(fill yes)
				)
			)
		)
		(pad "2" smd custom
			(at 0 0.4445 90)
			(size 0.1397 0.1397)
			(layers "F.Cu" "F.Mask" "F.Paste")
			(net "DRV_ACT_0")
			(options
				(clearance outline)
				(anchor circle)
			)
			(primitives
				(gr_poly
					(pts
						(arc
							(start -0.1778 -0.2794)
							(mid -0.249642 -0.249642)
							(end -0.2794 -0.1778)
						)
						(arc
							(start -0.2794 0.1778)
							(mid -0.249642 0.249642)
							(end -0.1778 0.2794)
						)
						(arc
							(start 0.1778 0.2794)
							(mid 0.249642 0.249642)
							(end 0.2794 0.1778)
						)
						(arc
							(start 0.2794 -0.1778)
							(mid 0.249642 -0.249642)
							(end 0.1778 -0.2794)
						)
					)
					(width 0)
					(fill yes)
				)
			)
		)
	)
	(footprint ""
		(layer "F.Cu")
		(at 217.762582 -270.355568 -90)
		(property "Reference" "C137"
			(at 0 0 270)
			(layer "F.SilkS")
			(hide yes)
			(effects
				(font
					(size 1.27 1.27)
				)
			)
		)
		(property "Value" "SCD01U50V2KX-1GP"
			(at 1.1811 -2.7051 270)
			(unlocked yes)
			(layer "F.Fab")
			(hide yes)
			(effects
				(font
					(size 1.016 1.016)
					(thickness 0.1524)
				)
			)
		)
		(property "Device Type" "C402H22"
			(at 1.1811 -4.2291 270)
			(unlocked yes)
			(layer "F.Fab")
			(hide yes)
			(effects
				(font
					(size 1.016 1.016)
					(thickness 0.1524)
				)
			)
		)
		(duplicate_pad_numbers_are_jumpers no)
		(fp_rect
			(start -0.4318 0.9525)
			(end 0.4318 -0.9525)
			(stroke
				(width 0)
				(type default)
			)
			(fill no)
			(layer "F.CrtYd")
		)
		(fp_rect
			(start -0.4318 0.9525)
			(end 0.4318 -0.9525)
			(stroke
				(width 0)
				(type default)
			)
			(fill no)
			(layer "F.Fab")
		)
		(pad "1" smd custom
			(at 0 -0.4445 270)
			(size 0.1524 0.1524)
			(layers "F.Cu" "F.Mask" "F.Paste")
			(net "SAS2X28_DRIVE_RX_P_B2")
			(options
				(clearance outline)
				(anchor circle)
			)
			(primitives
				(gr_poly
					(pts
						(arc
							(start 0.3048 -0.2032)
							(mid 0.275042 -0.275042)
							(end 0.2032 -0.3048)
						)
						(arc
							(start -0.2032 -0.3048)
							(mid -0.275042 -0.275042)
							(end -0.3048 -0.2032)
						)
						(arc
							(start -0.3048 0.2032)
							(mid -0.275042 0.275042)
							(end -0.2032 0.3048)
						)
						(arc
							(start 0.2032 0.3048)
							(mid 0.275042 0.275042)
							(end 0.3048 0.2032)
						)
					)
					(width 0)
					(fill yes)
				)
			)
		)
		(pad "2" smd custom
			(at 0 0.4445 270)
			(size 0.1524 0.1524)
			(layers "F.Cu" "F.Mask" "F.Paste")
			(net "SAS2X28_B_HDD2_RX_+")
			(options
				(clearance outline)
				(anchor circle)
			)
			(primitives
				(gr_poly
					(pts
						(arc
							(start 0.3048 -0.2032)
							(mid 0.275042 -0.275042)
							(end 0.2032 -0.3048)
						)
						(arc
							(start -0.2032 -0.3048)
							(mid -0.275042 -0.275042)
							(end -0.3048 -0.2032)
						)
						(arc
							(start -0.3048 0.2032)
							(mid -0.275042 0.275042)
							(end -0.2032 0.3048)
						)
						(arc
							(start 0.2032 0.3048)
							(mid 0.275042 0.275042)
							(end 0.3048 0.2032)
						)
					)
					(width 0)
					(fill yes)
				)
			)
		)
	)
	(footprint ""
		(layer "F.Cu")
		(at 229.615746 -26.1747 -90)
		(property "Reference" "PR9"
			(at 0 0 270)
			(layer "F.SilkS")
			(hide yes)
			(effects
				(font
					(size 1.27 1.27)
				)
			)
		)
		(property "Value" "76K8R2F-GP"
			(at 0.064008 -3.993896 270)
			(unlocked yes)
			(layer "F.Fab")
			(hide yes)
			(effects
				(font
					(size 1.016 1.016)
					(thickness 0.1524)
				)
			)
		)
		(property "Device Type" "R402H16"
			(at 0.064008 -5.517896 270)
			(unlocked yes)
			(layer "F.Fab")
			(hide yes)
			(effects
				(font
					(size 1.016 1.016)
					(thickness 0.1524)
				)
			)
		)
		(duplicate_pad_numbers_are_jumpers no)
		(fp_line
			(start -0.508 -0.9398)
			(end -0.508 0.9398)
			(stroke
				(width 0.1524)
				(type default)
			)
			(layer "F.SilkS")
		)
		(fp_line
			(start 0.508 -0.9398)
			(end -0.508 -0.9398)
			(stroke
				(width 0.1524)
				(type default)
			)
			(layer "F.SilkS")
		)
		(fp_rect
			(start -0.508 0.9398)
			(end 0.508 -0.9398)
			(stroke
				(width 0)
				(type default)
			)
			(fill no)
			(layer "F.CrtYd")
		)
		(fp_rect
			(start -0.508 0.9398)
			(end 0.508 -0.9398)
			(stroke
				(width 0)
				(type default)
			)
			(fill no)
			(layer "F.Fab")
		)
		(pad "1" smd custom
			(at 0 -0.4445 270)
			(size 0.1397 0.1397)
			(layers "F.Cu" "F.Mask" "F.Paste")
			(net "P5VA_ROVP")
			(options
				(clearance outline)
				(anchor circle)
			)
			(primitives
				(gr_poly
					(pts
						(arc
							(start -0.1778 -0.2794)
							(mid -0.249642 -0.249642)
							(end -0.2794 -0.1778)
						)
						(arc
							(start -0.2794 0.1778)
							(mid -0.249642 0.249642)
							(end -0.1778 0.2794)
						)
						(arc
							(start 0.1778 0.2794)
							(mid 0.249642 0.249642)
							(end 0.2794 0.1778)
						)
						(arc
							(start 0.2794 -0.1778)
							(mid 0.249642 -0.249642)
							(end 0.1778 -0.2794)
						)
					)
					(width 0)
					(fill yes)
				)
			)
		)
		(pad "2" smd custom
			(at 0 0.4445 270)
			(size 0.1397 0.1397)
			(layers "F.Cu" "F.Mask" "F.Paste")
			(net "P5VA")
			(options
				(clearance outline)
				(anchor circle)
			)
			(primitives
				(gr_poly
					(pts
						(arc
							(start -0.1778 -0.2794)
							(mid -0.249642 -0.249642)
							(end -0.2794 -0.1778)
						)
						(arc
							(start -0.2794 0.1778)
							(mid -0.249642 0.249642)
							(end -0.1778 0.2794)
						)
						(arc
							(start 0.1778 0.2794)
							(mid 0.249642 0.249642)
							(end 0.2794 0.1778)
						)
						(arc
							(start 0.2794 -0.1778)
							(mid 0.249642 -0.249642)
							(end 0.1778 -0.2794)
						)
					)
					(width 0)
					(fill yes)
				)
			)
		)
	)
	(footprint ""
		(layer "F.Cu")
		(at 77.495146 -7.013702)
		(property "Reference" "C335"
			(at 0 0 0)
			(layer "F.SilkS")
			(hide yes)
			(effects
				(font
					(size 1.27 1.27)
				)
			)
		)
		(property "Value" "SC10U25V6KX-1GP"
			(at -0.0762 -5.1308 0)
			(unlocked yes)
			(layer "F.Fab")
			(hide yes)
			(effects
				(font
					(size 1.016 1.016)
					(thickness 0.1524)
				)
			)
		)
		(property "Device Type" "C1206H71"
			(at -0.127 -6.6548 0)
			(unlocked yes)
			(layer "F.Fab")
			(hide yes)
			(effects
				(font
					(size 1.016 1.016)
					(thickness 0.1524)
				)
			)
		)
		(duplicate_pad_numbers_are_jumpers no)
		(fp_line
			(start -1.016 -2.2352)
			(end 1.016 -2.2352)
			(stroke
				(width 0.1524)
				(type default)
			)
			(layer "F.SilkS")
		)
		(fp_line
			(start -1.016 -0.8382)
			(end -1.016 -2.2352)
			(stroke
				(width 0.1524)
				(type default)
			)
			(layer "F.SilkS")
		)
		(fp_line
			(start -1.016 2.2352)
			(end -1.016 0.8382)
			(stroke
				(width 0.1524)
				(type default)
			)
			(layer "F.SilkS")
		)
		(fp_line
			(start 1.016 -2.2352)
			(end 1.016 -0.8382)
			(stroke
				(width 0.1524)
				(type default)
			)
			(layer "F.SilkS")
		)
		(fp_line
			(start 1.016 0.8382)
			(end 1.016 2.2352)
			(stroke
				(width 0.1524)
				(type default)
			)
			(layer "F.SilkS")
		)
		(fp_line
			(start 1.016 2.2352)
			(end -1.016 2.2352)
			(stroke
				(width 0.1524)
				(type default)
			)
			(layer "F.SilkS")
		)
		(fp_rect
			(start -1.0922 2.3114)
			(end 1.0922 -2.3114)
			(stroke
				(width 0)
				(type default)
			)
			(fill no)
			(layer "F.CrtYd")
		)
		(fp_poly
			(pts
				(xy 1.0922 -2.3114) (xy 1.0922 2.3114) (xy -1.0922 2.3114) (xy -1.0922 -2.3114)
			)
			(stroke
				(width 0)
				(type default)
			)
			(fill no)
			(layer "F.Fab")
		)
		(pad "1" smd rect
			(at 0 -1.397)
			(size 1.651 1.27)
			(layers "F.Cu" "F.Mask" "F.Paste")
			(net "P12V_HDD14")
		)
		(pad "2" smd rect
			(at 0 1.397)
			(size 1.651 1.27)
			(layers "F.Cu" "F.Mask" "F.Paste")
			(net "GND")
		)
	)
	(footprint ""
		(layer "F.Cu")
		(at 197.485 -179.832)
		(property "Reference" "C149"
			(at 0 0 0)
			(layer "F.SilkS")
			(hide yes)
			(effects
				(font
					(size 1.27 1.27)
				)
			)
		)
		(property "Value" "SCD1U10V2KX-5GP"
			(at 1.1811 -2.7051 0)
			(unlocked yes)
			(layer "F.Fab")
			(hide yes)
			(effects
				(font
					(size 1.016 1.016)
					(thickness 0.1524)
				)
			)
		)
		(property "Device Type" "C402H22"
			(at 1.1811 -4.2291 0)
			(unlocked yes)
			(layer "F.Fab")
			(hide yes)
			(effects
				(font
					(size 1.016 1.016)
					(thickness 0.1524)
				)
			)
		)
		(duplicate_pad_numbers_are_jumpers no)
		(fp_rect
			(start -0.4318 0.9525)
			(end 0.4318 -0.9525)
			(stroke
				(width 0)
				(type default)
			)
			(fill no)
			(layer "F.CrtYd")
		)
		(fp_rect
			(start -0.4318 0.9525)
			(end 0.4318 -0.9525)
			(stroke
				(width 0)
				(type default)
			)
			(fill no)
			(layer "F.Fab")
		)
		(pad "1" smd custom
			(at 0 -0.4445)
			(size 0.1524 0.1524)
			(layers "F.Cu" "F.Mask" "F.Paste")
			(net "P3V3")
			(options
				(clearance outline)
				(anchor circle)
			)
			(primitives
				(gr_poly
					(pts
						(arc
							(start 0.3048 -0.2032)
							(mid 0.275042 -0.275042)
							(end 0.2032 -0.3048)
						)
						(arc
							(start -0.2032 -0.3048)
							(mid -0.275042 -0.275042)
							(end -0.3048 -0.2032)
						)
						(arc
							(start -0.3048 0.2032)
							(mid -0.275042 0.275042)
							(end -0.2032 0.3048)
						)
						(arc
							(start 0.2032 0.3048)
							(mid 0.275042 0.275042)
							(end 0.3048 0.2032)
						)
					)
					(width 0)
					(fill yes)
				)
			)
		)
		(pad "2" smd custom
			(at 0 0.4445)
			(size 0.1524 0.1524)
			(layers "F.Cu" "F.Mask" "F.Paste")
			(net "GND")
			(options
				(clearance outline)
				(anchor circle)
			)
			(primitives
				(gr_poly
					(pts
						(arc
							(start 0.3048 -0.2032)
							(mid 0.275042 -0.275042)
							(end 0.2032 -0.3048)
						)
						(arc
							(start -0.2032 -0.3048)
							(mid -0.275042 -0.275042)
							(end -0.3048 -0.2032)
						)
						(arc
							(start -0.3048 0.2032)
							(mid -0.275042 0.275042)
							(end -0.2032 0.3048)
						)
						(arc
							(start 0.2032 0.3048)
							(mid 0.275042 0.275042)
							(end 0.3048 0.2032)
						)
					)
					(width 0)
					(fill yes)
				)
			)
		)
	)
)
